(kicad_pcb
	(version 20260206)
	(generator "pcbnew")
	(generator_version "10.0")
	(general
		(thickness 1.6)
		(legacy_teardrops no)
	)
	(paper "A4")
	(title_block
		(title "12092022_DA0F0TMDCD0_F0T_Management_Board_D_brd_V3_OCP.brd")
		(comment 1 "Grand Teton / footprints 1257-1262 of 1440")
	)
	(layers
		(0 "F.Cu" signal "TOP")
		(4 "In1.Cu" signal "GND")
		(6 "In2.Cu" signal "IN1")
		(8 "In3.Cu" signal "GND1")
		(10 "In4.Cu" signal "IN2")
		(12 "In5.Cu" signal "VCC")
		(14 "In6.Cu" signal "VCC1")
		(16 "In7.Cu" signal "IN3")
		(18 "In8.Cu" signal "GND2")
		(20 "In9.Cu" signal "IN4")
		(22 "In10.Cu" signal "GND3")
		(2 "B.Cu" signal "BOTTOM")
		(9 "F.Adhes" user "F.Adhesive")
		(11 "B.Adhes" user "B.Adhesive")
		(13 "F.Paste" user "Package Geometry/Pastemask Top")
		(15 "B.Paste" user "Package Geometry/Pastemask Bottom")
		(5 "F.SilkS" user "Ref Des/Silkscreen Top")
		(7 "B.SilkS" user "Ref Des/Silkscreen Bottom")
		(1 "F.Mask" user "Board Geometry/Soldermask Top")
		(3 "B.Mask" user "Board Geometry/Soldermask Bottom")
		(17 "Dwgs.User" user "User.Drawings")
		(19 "Cmts.User" user "User.Comments")
		(21 "Eco1.User" user "User.Eco1")
		(23 "Eco2.User" user "User.Eco2")
		(25 "Edge.Cuts" user "Board Geometry/Outline")
		(27 "Margin" user)
		(31 "F.CrtYd" user "Package Geometry/Place Bound Top")
		(29 "B.CrtYd" user "Package Geometry/Place Bound Bottom")
		(35 "F.Fab" user "Ref Des/Assembly Top")
		(33 "B.Fab" user "Ref Des/Assembly Bottom")
	)
	(footprint ""
		(layer "B.Cu")
		(at 79.739744 -35.540188 -90)
		(property "Reference" "R346"
			(at 0 0 90)
			(layer "B.SilkS")
			(hide yes)
			(effects
				(font
					(size 1.27 1.27)
				)
				(justify mirror)
			)
		)
		(property "Value" ""
			(at 0 0 90)
			(layer "B.Fab")
			(effects
				(font
					(size 1.27 1.27)
				)
				(justify mirror)
			)
		)
		(duplicate_pad_numbers_are_jumpers no)
		(fp_line
			(start -0.7874 0.4064)
			(end 0.7874 0.4064)
			(stroke
				(width 0.1524)
				(type default)
			)
			(layer "B.SilkS")
		)
		(fp_line
			(start 0.7874 0.4064)
			(end 0.7874 -0.4064)
			(stroke
				(width 0.1524)
				(type default)
			)
			(layer "B.SilkS")
		)
		(fp_line
			(start -0.7874 -0.4064)
			(end -0.7874 0.4064)
			(stroke
				(width 0.1524)
				(type default)
			)
			(layer "B.SilkS")
		)
		(fp_line
			(start 0.7874 -0.4064)
			(end -0.7874 -0.4064)
			(stroke
				(width 0.1524)
				(type default)
			)
			(layer "B.SilkS")
		)
		(fp_line
			(start -0.67945 0.3048)
			(end -0.120396 0.3048)
			(stroke
				(width 0.1)
				(type default)
			)
			(layer "B.Fab")
		)
		(fp_line
			(start -0.120396 0.3048)
			(end -0.120396 0.2794)
			(stroke
				(width 0.1)
				(type default)
			)
			(layer "B.Fab")
		)
		(fp_line
			(start 0.12065 0.3048)
			(end 0.67945 0.3048)
			(stroke
				(width 0.1)
				(type default)
			)
			(layer "B.Fab")
		)
		(fp_line
			(start 0.67945 0.3048)
			(end 0.67945 -0.305054)
			(stroke
				(width 0.1)
				(type default)
			)
			(layer "B.Fab")
		)
		(fp_line
			(start -0.120396 0.2794)
			(end 0.12065 0.2794)
			(stroke
				(width 0.1)
				(type default)
			)
			(layer "B.Fab")
		)
		(fp_line
			(start 0.12065 0.2794)
			(end 0.12065 0.3048)
			(stroke
				(width 0.1)
				(type default)
			)
			(layer "B.Fab")
		)
		(fp_line
			(start -0.12065 -0.2794)
			(end -0.12065 -0.3048)
			(stroke
				(width 0.1)
				(type default)
			)
			(layer "B.Fab")
		)
		(fp_line
			(start 0.12065 -0.2794)
			(end -0.12065 -0.2794)
			(stroke
				(width 0.1)
				(type default)
			)
			(layer "B.Fab")
		)
		(fp_line
			(start -0.67945 -0.3048)
			(end -0.67945 0.3048)
			(stroke
				(width 0.1)
				(type default)
			)
			(layer "B.Fab")
		)
		(fp_line
			(start -0.12065 -0.3048)
			(end -0.67945 -0.3048)
			(stroke
				(width 0.1)
				(type default)
			)
			(layer "B.Fab")
		)
		(fp_line
			(start 0.12065 -0.305054)
			(end 0.12065 -0.2794)
			(stroke
				(width 0.1)
				(type default)
			)
			(layer "B.Fab")
		)
		(fp_line
			(start 0.67945 -0.305054)
			(end 0.12065 -0.305054)
			(stroke
				(width 0.1)
				(type default)
			)
			(layer "B.Fab")
		)
		(pad "1" smd circle
			(at 0.40005 0 90)
			(size 0 0)
			(layers "B.Cu" "B.Mask" "B.Paste")
			(net "GND")
		)
		(pad "2" smd circle
			(at -0.40005 0 90)
			(size 0 0)
			(layers "B.Cu" "B.Mask" "B.Paste")
			(net "M_BMC_DDR4_MBA0")
		)
	)
	(footprint ""
		(layer "B.Cu")
		(at 54.93131 -46.073314 90)
		(property "Reference" "C89"
			(at 0 0 90)
			(layer "B.SilkS")
			(hide yes)
			(effects
				(font
					(size 1.27 1.27)
				)
				(justify mirror)
			)
		)
		(property "Value" ""
			(at 0 0 90)
			(layer "B.Fab")
			(effects
				(font
					(size 1.27 1.27)
				)
				(justify mirror)
			)
		)
		(duplicate_pad_numbers_are_jumpers no)
		(fp_line
			(start 0.7874 -0.4064)
			(end -0.7874 -0.4064)
			(stroke
				(width 0.1524)
				(type default)
			)
			(layer "B.SilkS")
		)
		(fp_line
			(start -0.7874 -0.4064)
			(end -0.7874 0.4064)
			(stroke
				(width 0.1524)
				(type default)
			)
			(layer "B.SilkS")
		)
		(fp_line
			(start 0.7874 0.4064)
			(end 0.7874 -0.4064)
			(stroke
				(width 0.1524)
				(type default)
			)
			(layer "B.SilkS")
		)
		(fp_line
			(start -0.7874 0.4064)
			(end 0.7874 0.4064)
			(stroke
				(width 0.1524)
				(type default)
			)
			(layer "B.SilkS")
		)
		(fp_line
			(start 0.67945 -0.305054)
			(end 0.12065 -0.305054)
			(stroke
				(width 0.1)
				(type default)
			)
			(layer "B.Fab")
		)
		(fp_line
			(start 0.12065 -0.305054)
			(end 0.12065 -0.2794)
			(stroke
				(width 0.1)
				(type default)
			)
			(layer "B.Fab")
		)
		(fp_line
			(start -0.12065 -0.3048)
			(end -0.67945 -0.3048)
			(stroke
				(width 0.1)
				(type default)
			)
			(layer "B.Fab")
		)
		(fp_line
			(start -0.67945 -0.3048)
			(end -0.67945 0.3048)
			(stroke
				(width 0.1)
				(type default)
			)
			(layer "B.Fab")
		)
		(fp_line
			(start 0.12065 -0.2794)
			(end -0.12065 -0.2794)
			(stroke
				(width 0.1)
				(type default)
			)
			(layer "B.Fab")
		)
		(fp_line
			(start -0.12065 -0.2794)
			(end -0.12065 -0.3048)
			(stroke
				(width 0.1)
				(type default)
			)
			(layer "B.Fab")
		)
		(fp_line
			(start 0.12065 0.2794)
			(end 0.12065 0.3048)
			(stroke
				(width 0.1)
				(type default)
			)
			(layer "B.Fab")
		)
		(fp_line
			(start -0.120396 0.2794)
			(end 0.12065 0.2794)
			(stroke
				(width 0.1)
				(type default)
			)
			(layer "B.Fab")
		)
		(fp_line
			(start 0.67945 0.3048)
			(end 0.67945 -0.305054)
			(stroke
				(width 0.1)
				(type default)
			)
			(layer "B.Fab")
		)
		(fp_line
			(start 0.12065 0.3048)
			(end 0.67945 0.3048)
			(stroke
				(width 0.1)
				(type default)
			)
			(layer "B.Fab")
		)
		(fp_line
			(start -0.120396 0.3048)
			(end -0.120396 0.2794)
			(stroke
				(width 0.1)
				(type default)
			)
			(layer "B.Fab")
		)
		(fp_line
			(start -0.67945 0.3048)
			(end -0.120396 0.3048)
			(stroke
				(width 0.1)
				(type default)
			)
			(layer "B.Fab")
		)
		(pad "1" smd circle
			(at 0.40005 0 270)
			(size 0 0)
			(layers "B.Cu" "B.Mask" "B.Paste")
			(net "P1V8_AUX")
		)
		(pad "2" smd circle
			(at -0.40005 0 270)
			(size 0 0)
			(layers "B.Cu" "B.Mask" "B.Paste")
			(net "GND")
		)
	)
	(footprint ""
		(layer "B.Cu")
		(at 79.739744 -37.559488 90)
		(property "Reference" "R371"
			(at 0 0 90)
			(layer "B.SilkS")
			(hide yes)
			(effects
				(font
					(size 1.27 1.27)
				)
				(justify mirror)
			)
		)
		(property "Value" ""
			(at 0 0 90)
			(layer "B.Fab")
			(effects
				(font
					(size 1.27 1.27)
				)
				(justify mirror)
			)
		)
		(duplicate_pad_numbers_are_jumpers no)
		(fp_line
			(start 0.7874 -0.4064)
			(end -0.7874 -0.4064)
			(stroke
				(width 0.1524)
				(type default)
			)
			(layer "B.SilkS")
		)
		(fp_line
			(start -0.7874 -0.4064)
			(end -0.7874 0.4064)
			(stroke
				(width 0.1524)
				(type default)
			)
			(layer "B.SilkS")
		)
		(fp_line
			(start 0.7874 0.4064)
			(end 0.7874 -0.4064)
			(stroke
				(width 0.1524)
				(type default)
			)
			(layer "B.SilkS")
		)
		(fp_line
			(start -0.7874 0.4064)
			(end 0.7874 0.4064)
			(stroke
				(width 0.1524)
				(type default)
			)
			(layer "B.SilkS")
		)
		(fp_line
			(start 0.67945 -0.305054)
			(end 0.12065 -0.305054)
			(stroke
				(width 0.1)
				(type default)
			)
			(layer "B.Fab")
		)
		(fp_line
			(start 0.12065 -0.305054)
			(end 0.12065 -0.2794)
			(stroke
				(width 0.1)
				(type default)
			)
			(layer "B.Fab")
		)
		(fp_line
			(start -0.12065 -0.3048)
			(end -0.67945 -0.3048)
			(stroke
				(width 0.1)
				(type default)
			)
			(layer "B.Fab")
		)
		(fp_line
			(start -0.67945 -0.3048)
			(end -0.67945 0.3048)
			(stroke
				(width 0.1)
				(type default)
			)
			(layer "B.Fab")
		)
		(fp_line
			(start 0.12065 -0.2794)
			(end -0.12065 -0.2794)
			(stroke
				(width 0.1)
				(type default)
			)
			(layer "B.Fab")
		)
		(fp_line
			(start -0.12065 -0.2794)
			(end -0.12065 -0.3048)
			(stroke
				(width 0.1)
				(type default)
			)
			(layer "B.Fab")
		)
		(fp_line
			(start 0.12065 0.2794)
			(end 0.12065 0.3048)
			(stroke
				(width 0.1)
				(type default)
			)
			(layer "B.Fab")
		)
		(fp_line
			(start -0.120396 0.2794)
			(end 0.12065 0.2794)
			(stroke
				(width 0.1)
				(type default)
			)
			(layer "B.Fab")
		)
		(fp_line
			(start 0.67945 0.3048)
			(end 0.67945 -0.305054)
			(stroke
				(width 0.1)
				(type default)
			)
			(layer "B.Fab")
		)
		(fp_line
			(start 0.12065 0.3048)
			(end 0.67945 0.3048)
			(stroke
				(width 0.1)
				(type default)
			)
			(layer "B.Fab")
		)
		(fp_line
			(start -0.120396 0.3048)
			(end -0.120396 0.2794)
			(stroke
				(width 0.1)
				(type default)
			)
			(layer "B.Fab")
		)
		(fp_line
			(start -0.67945 0.3048)
			(end -0.120396 0.3048)
			(stroke
				(width 0.1)
				(type default)
			)
			(layer "B.Fab")
		)
		(pad "1" smd circle
			(at 0.40005 0 270)
			(size 0 0)
			(layers "B.Cu" "B.Mask" "B.Paste")
			(net "M_BMC_DDR4_MBA0")
		)
		(pad "2" smd circle
			(at -0.40005 0 270)
			(size 0 0)
			(layers "B.Cu" "B.Mask" "B.Paste")
			(net "P1V2_AUX")
		)
	)
	(footprint ""
		(layer "B.Cu")
		(at 29.8196 -106.2482 -90)
		(property "Reference" "R77"
			(at 0 0 90)
			(layer "B.SilkS")
			(hide yes)
			(effects
				(font
					(size 1.27 1.27)
				)
				(justify mirror)
			)
		)
		(property "Value" ""
			(at 0 0 90)
			(layer "B.Fab")
			(effects
				(font
					(size 1.27 1.27)
				)
				(justify mirror)
			)
		)
		(duplicate_pad_numbers_are_jumpers no)
		(fp_line
			(start -0.7874 0.4064)
			(end 0.7874 0.4064)
			(stroke
				(width 0.1524)
				(type default)
			)
			(layer "B.SilkS")
		)
		(fp_line
			(start 0.7874 0.4064)
			(end 0.7874 -0.4064)
			(stroke
				(width 0.1524)
				(type default)
			)
			(layer "B.SilkS")
		)
		(fp_line
			(start -0.7874 -0.4064)
			(end -0.7874 0.4064)
			(stroke
				(width 0.1524)
				(type default)
			)
			(layer "B.SilkS")
		)
		(fp_line
			(start 0.7874 -0.4064)
			(end -0.7874 -0.4064)
			(stroke
				(width 0.1524)
				(type default)
			)
			(layer "B.SilkS")
		)
		(fp_line
			(start -0.67945 0.3048)
			(end -0.120396 0.3048)
			(stroke
				(width 0.1)
				(type default)
			)
			(layer "B.Fab")
		)
		(fp_line
			(start -0.120396 0.3048)
			(end -0.120396 0.2794)
			(stroke
				(width 0.1)
				(type default)
			)
			(layer "B.Fab")
		)
		(fp_line
			(start 0.12065 0.3048)
			(end 0.67945 0.3048)
			(stroke
				(width 0.1)
				(type default)
			)
			(layer "B.Fab")
		)
		(fp_line
			(start 0.67945 0.3048)
			(end 0.67945 -0.305054)
			(stroke
				(width 0.1)
				(type default)
			)
			(layer "B.Fab")
		)
		(fp_line
			(start -0.120396 0.2794)
			(end 0.12065 0.2794)
			(stroke
				(width 0.1)
				(type default)
			)
			(layer "B.Fab")
		)
		(fp_line
			(start 0.12065 0.2794)
			(end 0.12065 0.3048)
			(stroke
				(width 0.1)
				(type default)
			)
			(layer "B.Fab")
		)
		(fp_line
			(start -0.12065 -0.2794)
			(end -0.12065 -0.3048)
			(stroke
				(width 0.1)
				(type default)
			)
			(layer "B.Fab")
		)
		(fp_line
			(start 0.12065 -0.2794)
			(end -0.12065 -0.2794)
			(stroke
				(width 0.1)
				(type default)
			)
			(layer "B.Fab")
		)
		(fp_line
			(start -0.67945 -0.3048)
			(end -0.67945 0.3048)
			(stroke
				(width 0.1)
				(type default)
			)
			(layer "B.Fab")
		)
		(fp_line
			(start -0.12065 -0.3048)
			(end -0.67945 -0.3048)
			(stroke
				(width 0.1)
				(type default)
			)
			(layer "B.Fab")
		)
		(fp_line
			(start 0.12065 -0.305054)
			(end 0.12065 -0.2794)
			(stroke
				(width 0.1)
				(type default)
			)
			(layer "B.Fab")
		)
		(fp_line
			(start 0.67945 -0.305054)
			(end 0.12065 -0.305054)
			(stroke
				(width 0.1)
				(type default)
			)
			(layer "B.Fab")
		)
		(pad "1" smd circle
			(at 0.40005 0 90)
			(size 0 0)
			(layers "B.Cu" "B.Mask" "B.Paste")
			(net "P3V3_AUX")
		)
		(pad "2" smd circle
			(at -0.40005 0 90)
			(size 0 0)
			(layers "B.Cu" "B.Mask" "B.Paste")
			(net "SGPIO_LD_0")
		)
	)
	(footprint ""
		(layer "B.Cu")
		(at 22.5298 -83.693 -90)
		(property "Reference" "R807"
			(at 0 0 90)
			(layer "B.SilkS")
			(hide yes)
			(effects
				(font
					(size 1.27 1.27)
				)
				(justify mirror)
			)
		)
		(property "Value" ""
			(at 0 0 90)
			(layer "B.Fab")
			(effects
				(font
					(size 1.27 1.27)
				)
				(justify mirror)
			)
		)
		(duplicate_pad_numbers_are_jumpers no)
		(fp_line
			(start -0.7874 0.4064)
			(end 0.7874 0.4064)
			(stroke
				(width 0.1524)
				(type default)
			)
			(layer "B.SilkS")
		)
		(fp_line
			(start 0.7874 0.4064)
			(end 0.7874 -0.4064)
			(stroke
				(width 0.1524)
				(type default)
			)
			(layer "B.SilkS")
		)
		(fp_line
			(start -0.7874 -0.4064)
			(end -0.7874 0.4064)
			(stroke
				(width 0.1524)
				(type default)
			)
			(layer "B.SilkS")
		)
		(fp_line
			(start 0.7874 -0.4064)
			(end -0.7874 -0.4064)
			(stroke
				(width 0.1524)
				(type default)
			)
			(layer "B.SilkS")
		)
		(fp_line
			(start -0.67945 0.3048)
			(end -0.120396 0.3048)
			(stroke
				(width 0.1)
				(type default)
			)
			(layer "B.Fab")
		)
		(fp_line
			(start -0.120396 0.3048)
			(end -0.120396 0.2794)
			(stroke
				(width 0.1)
				(type default)
			)
			(layer "B.Fab")
		)
		(fp_line
			(start 0.12065 0.3048)
			(end 0.67945 0.3048)
			(stroke
				(width 0.1)
				(type default)
			)
			(layer "B.Fab")
		)
		(fp_line
			(start 0.67945 0.3048)
			(end 0.67945 -0.305054)
			(stroke
				(width 0.1)
				(type default)
			)
			(layer "B.Fab")
		)
		(fp_line
			(start -0.120396 0.2794)
			(end 0.12065 0.2794)
			(stroke
				(width 0.1)
				(type default)
			)
			(layer "B.Fab")
		)
		(fp_line
			(start 0.12065 0.2794)
			(end 0.12065 0.3048)
			(stroke
				(width 0.1)
				(type default)
			)
			(layer "B.Fab")
		)
		(fp_line
			(start -0.12065 -0.2794)
			(end -0.12065 -0.3048)
			(stroke
				(width 0.1)
				(type default)
			)
			(layer "B.Fab")
		)
		(fp_line
			(start 0.12065 -0.2794)
			(end -0.12065 -0.2794)
			(stroke
				(width 0.1)
				(type default)
			)
			(layer "B.Fab")
		)
		(fp_line
			(start -0.67945 -0.3048)
			(end -0.67945 0.3048)
			(stroke
				(width 0.1)
				(type default)
			)
			(layer "B.Fab")
		)
		(fp_line
			(start -0.12065 -0.3048)
			(end -0.67945 -0.3048)
			(stroke
				(width 0.1)
				(type default)
			)
			(layer "B.Fab")
		)
		(fp_line
			(start 0.12065 -0.305054)
			(end 0.12065 -0.2794)
			(stroke
				(width 0.1)
				(type default)
			)
			(layer "B.Fab")
		)
		(fp_line
			(start 0.67945 -0.305054)
			(end 0.12065 -0.305054)
			(stroke
				(width 0.1)
				(type default)
			)
			(layer "B.Fab")
		)
		(pad "1" smd circle
			(at 0.40005 0 90)
			(size 0 0)
			(layers "B.Cu" "B.Mask" "B.Paste")
			(net "CLK_25M_OSC_FPGA_R")
		)
		(pad "2" smd circle
			(at -0.40005 0 90)
			(size 0 0)
			(layers "B.Cu" "B.Mask" "B.Paste")
			(net "CLK_25M_OSC_FPGA")
		)
	)
	(footprint ""
		(layer "B.Cu")
		(at 43.8912 -88.4936 90)
		(property "Reference" "R694"
			(at 0 0 90)
			(layer "B.SilkS")
			(hide yes)
			(effects
				(font
					(size 1.27 1.27)
				)
				(justify mirror)
			)
		)
		(property "Value" ""
			(at 0 0 90)
			(layer "B.Fab")
			(effects
				(font
					(size 1.27 1.27)
				)
				(justify mirror)
			)
		)
		(duplicate_pad_numbers_are_jumpers no)
		(fp_line
			(start 0.7874 -0.4064)
			(end -0.7874 -0.4064)
			(stroke
				(width 0.1524)
				(type default)
			)
			(layer "B.SilkS")
		)
		(fp_line
			(start -0.7874 -0.4064)
			(end -0.7874 0.4064)
			(stroke
				(width 0.1524)
				(type default)
			)
			(layer "B.SilkS")
		)
		(fp_line
			(start 0.7874 0.4064)
			(end 0.7874 -0.4064)
			(stroke
				(width 0.1524)
				(type default)
			)
			(layer "B.SilkS")
		)
		(fp_line
			(start -0.7874 0.4064)
			(end 0.7874 0.4064)
			(stroke
				(width 0.1524)
				(type default)
			)
			(layer "B.SilkS")
		)
		(fp_line
			(start 0.67945 -0.305054)
			(end 0.12065 -0.305054)
			(stroke
				(width 0.1)
				(type default)
			)
			(layer "B.Fab")
		)
		(fp_line
			(start 0.12065 -0.305054)
			(end 0.12065 -0.2794)
			(stroke
				(width 0.1)
				(type default)
			)
			(layer "B.Fab")
		)
		(fp_line
			(start -0.12065 -0.3048)
			(end -0.67945 -0.3048)
			(stroke
				(width 0.1)
				(type default)
			)
			(layer "B.Fab")
		)
		(fp_line
			(start -0.67945 -0.3048)
			(end -0.67945 0.3048)
			(stroke
				(width 0.1)
				(type default)
			)
			(layer "B.Fab")
		)
		(fp_line
			(start 0.12065 -0.2794)
			(end -0.12065 -0.2794)
			(stroke
				(width 0.1)
				(type default)
			)
			(layer "B.Fab")
		)
		(fp_line
			(start -0.12065 -0.2794)
			(end -0.12065 -0.3048)
			(stroke
				(width 0.1)
				(type default)
			)
			(layer "B.Fab")
		)
		(fp_line
			(start 0.12065 0.2794)
			(end 0.12065 0.3048)
			(stroke
				(width 0.1)
				(type default)
			)
			(layer "B.Fab")
		)
		(fp_line
			(start -0.120396 0.2794)
			(end 0.12065 0.2794)
			(stroke
				(width 0.1)
				(type default)
			)
			(layer "B.Fab")
		)
		(fp_line
			(start 0.67945 0.3048)
			(end 0.67945 -0.305054)
			(stroke
				(width 0.1)
				(type default)
			)
			(layer "B.Fab")
		)
		(fp_line
			(start 0.12065 0.3048)
			(end 0.67945 0.3048)
			(stroke
				(width 0.1)
				(type default)
			)
			(layer "B.Fab")
		)
		(fp_line
			(start -0.120396 0.3048)
			(end -0.120396 0.2794)
			(stroke
				(width 0.1)
				(type default)
			)
			(layer "B.Fab")
		)
		(fp_line
			(start -0.67945 0.3048)
			(end -0.120396 0.3048)
			(stroke
				(width 0.1)
				(type default)
			)
			(layer "B.Fab")
		)
		(pad "1" smd circle
			(at 0.40005 0 270)
			(size 0 0)
			(layers "B.Cu" "B.Mask" "B.Paste")
			(net "USB3_MUX_PD")
		)
		(pad "2" smd circle
			(at -0.40005 0 270)
			(size 0 0)
			(layers "B.Cu" "B.Mask" "B.Paste")
			(net "GND")
		)
	)
)
